(kicad_pcb
	(version 20260206)
	(generator "pcbnew")
	(generator_version "10.0")
	(general
		(thickness 1.6)
		(legacy_teardrops no)
	)
	(paper "A4")
	(title_block
		(title "04192023_DAF0TMB3IC0_F0TG_MB_C_brd_V02_OCP.brd")
		(comment 1 "Grand Teton / footprint 3102 of 8354 (U6011), pads 112-223 of 354")
	)
	(layers
		(0 "F.Cu" signal "TOP")
		(4 "In1.Cu" signal "GND")
		(6 "In2.Cu" signal "IN1")
		(8 "In3.Cu" signal "GND1")
		(10 "In4.Cu" signal "IN2")
		(12 "In5.Cu" signal "GND2")
		(14 "In6.Cu" signal "IN3")
		(16 "In7.Cu" signal "GND3")
		(18 "In8.Cu" signal "VCC")
		(20 "In9.Cu" signal "VCC1")
		(22 "In10.Cu" signal "GND4")
		(24 "In11.Cu" signal "IN4")
		(26 "In12.Cu" signal "GND5")
		(28 "In13.Cu" signal "IN5")
		(30 "In14.Cu" signal "GND6")
		(32 "In15.Cu" signal "IN6")
		(34 "In16.Cu" signal "GND7")
		(2 "B.Cu" signal "BOTTOM")
		(9 "F.Adhes" user "F.Adhesive")
		(11 "B.Adhes" user "B.Adhesive")
		(13 "F.Paste" user "Package Geometry/Pastemask Top")
		(15 "B.Paste" user "Package Geometry/Pastemask Bottom")
		(5 "F.SilkS" user "Ref Des/Silkscreen Top")
		(7 "B.SilkS" user "Ref Des/Silkscreen Bottom")
		(1 "F.Mask" user "Board Geometry/Soldermask Top")
		(3 "B.Mask" user "Board Geometry/Soldermask Bottom")
		(17 "Dwgs.User" user "User.Drawings")
		(19 "Cmts.User" user "User.Comments")
		(21 "Eco1.User" user "User.Eco1")
		(23 "Eco2.User" user "User.Eco2")
		(25 "Edge.Cuts" user "Board Geometry/Outline")
		(27 "Margin" user)
		(31 "F.CrtYd" user "Package Geometry/Place Bound Top")
		(29 "B.CrtYd" user "Package Geometry/Place Bound Bottom")
		(35 "F.Fab" user "Ref Des/Assembly Top")
		(33 "B.Fab" user "Ref Des/Assembly Bottom")
	)
	(footprint ""
		(layer "F.Cu")
		(at 344.9955 -395.724634)
		(property "Reference" "U6011"
			(at -8.11784 -7.526528 0)
			(unlocked yes)
			(layer "F.SilkS")
			(effects
				(font
					(size 0.7874 0.5842)
					(thickness 0.1524)
				)
				(justify left)
			)
		)
		(property "Value" ""
			(at 0 0 0)
			(layer "F.Fab")
			(effects
				(font
					(size 1.27 1.27)
				)
			)
		)
		(duplicate_pad_numbers_are_jumpers no)
		(pad "BV32" smd circle
			(at 1.20269 2.724912)
			(size 0.381 0.381)
			(layers "F.Cu" "F.Mask" "F.Paste")
			(net "GND")
		)
		(pad "BW2" smd circle
			(at 1.150112 -3.41884)
			(size 0.3048 0.3048)
			(layers "F.Cu" "F.Mask" "F.Paste")
			(net "GND")
		)
		(pad "BW34" smd circle
			(at 1.150112 3.420364)
			(size 0.3048 0.3048)
			(layers "F.Cu" "F.Mask" "F.Paste")
			(net "GND")
		)
		(pad "BY1" smd oval
			(at 0.849884 -3.938524)
			(size 0.254 0.3302)
			(layers "F.Cu" "F.Mask" "F.Paste")
			(net "GND")
		)
		(pad "BY35" smd oval
			(at 0.849884 3.940048)
			(size 0.254 0.3302)
			(layers "F.Cu" "F.Mask" "F.Paste")
			(net "GND")
		)
		(pad "C2" smd circle
			(at 10.750042 -3.41884)
			(size 0.3048 0.3048)
			(layers "F.Cu" "F.Mask" "F.Paste")
			(net "NCF_CPU0_P1_GND")
		)
		(pad "C34" smd circle
			(at 10.750042 3.420364)
			(size 0.3048 0.3048)
			(layers "F.Cu" "F.Mask" "F.Paste")
			(net "NCF_CPU0_P1_GND")
		)
		(pad "CA7" smd circle
			(at 0.80264 -2.12471)
			(size 0.381 0.381)
			(layers "F.Cu" "F.Mask" "F.Paste")
			(net "P5E_CPU0_P1_TX_BUF_DP<8>")
		)
		(pad "CA26" smd circle
			(at 0.80264 1.339342)
			(size 0.381 0.381)
			(layers "F.Cu" "F.Mask" "F.Paste")
			(net "P5E_CPU0_P1_RX_DP<8>")
		)
		(pad "CB2" smd circle
			(at 0.54991 -3.41884)
			(size 0.3048 0.3048)
			(layers "F.Cu" "F.Mask" "F.Paste")
			(net "P5E_CPU0_P1_RX_BUF_DN<8>")
		)
		(pad "CB34" smd circle
			(at 0.54991 3.420364)
			(size 0.3048 0.3048)
			(layers "F.Cu" "F.Mask" "F.Paste")
			(net "P5E_CPU0_P1_TX_C_DN<8>")
		)
		(pad "CC10" smd circle
			(at 0.40259 -1.431798)
			(size 0.381 0.381)
			(layers "F.Cu" "F.Mask" "F.Paste")
			(net "P5E_CPU0_P1_TX_BUF_DN<8>")
		)
		(pad "CC29" smd circle
			(at 0.40259 2.032254)
			(size 0.381 0.381)
			(layers "F.Cu" "F.Mask" "F.Paste")
			(net "P5E_CPU0_P1_RX_DN<8>")
		)
		(pad "CD1" smd oval
			(at 0.249936 -3.938524)
			(size 0.254 0.3302)
			(layers "F.Cu" "F.Mask" "F.Paste")
			(net "P5E_CPU0_P1_RX_BUF_DP<8>")
		)
		(pad "CD35" smd oval
			(at 0.249936 3.940048)
			(size 0.254 0.3302)
			(layers "F.Cu" "F.Mask" "F.Paste")
			(net "P5E_CPU0_P1_TX_C_DP<8>")
		)
		(pad "CE4" smd circle
			(at 0.00254 -2.817368)
			(size 0.381 0.381)
			(layers "F.Cu" "F.Mask" "F.Paste")
			(net "GND")
		)
		(pad "CE13" smd circle
			(at 0.00254 -0.79629)
			(size 0.3048 0.3048)
			(layers "F.Cu" "F.Mask" "F.Paste")
			(net "GND")
		)
		(pad "CE17" smd circle
			(at 0.00254 -0.296164)
			(size 0.3048 0.3048)
			(layers "F.Cu" "F.Mask" "F.Paste")
			(net "P1V8_CPU0_RT1_1A")
		)
		(pad "CE20" smd circle
			(at 0.00254 0.203708)
			(size 0.3048 0.3048)
			(layers "F.Cu" "F.Mask" "F.Paste")
			(net "P1V8_CPU0_RT1_1A")
		)
		(pad "CE22" smd circle
			(at 0.00254 0.703834)
			(size 0.3048 0.3048)
			(layers "F.Cu" "F.Mask" "F.Paste")
			(net "GND")
		)
		(pad "CE32" smd circle
			(at 0.00254 2.724912)
			(size 0.381 0.381)
			(layers "F.Cu" "F.Mask" "F.Paste")
			(net "GND")
		)
		(pad "CF2" smd circle
			(at -0.050038 -3.41884)
			(size 0.3048 0.3048)
			(layers "F.Cu" "F.Mask" "F.Paste")
			(net "GND")
		)
		(pad "CF34" smd circle
			(at -0.050038 3.420364)
			(size 0.3048 0.3048)
			(layers "F.Cu" "F.Mask" "F.Paste")
			(net "GND")
		)
		(pad "CG1" smd oval
			(at -0.350012 -3.938524)
			(size 0.254 0.3302)
			(layers "F.Cu" "F.Mask" "F.Paste")
			(net "GND")
		)
		(pad "CG35" smd oval
			(at -0.350012 3.940048)
			(size 0.254 0.3302)
			(layers "F.Cu" "F.Mask" "F.Paste")
			(net "GND")
		)
		(pad "CH7" smd circle
			(at -0.39751 -2.12471)
			(size 0.381 0.381)
			(layers "F.Cu" "F.Mask" "F.Paste")
			(net "P5E_CPU0_P1_TX_BUF_DP<7>")
		)
		(pad "CH26" smd circle
			(at -0.39751 1.339342)
			(size 0.381 0.381)
			(layers "F.Cu" "F.Mask" "F.Paste")
			(net "P5E_CPU0_P1_RX_DP<7>")
		)
		(pad "CJ2" smd circle
			(at -0.649986 -3.41884)
			(size 0.3048 0.3048)
			(layers "F.Cu" "F.Mask" "F.Paste")
			(net "P5E_CPU0_P1_RX_BUF_DN<7>")
		)
		(pad "CJ34" smd circle
			(at -0.649986 3.420364)
			(size 0.3048 0.3048)
			(layers "F.Cu" "F.Mask" "F.Paste")
			(net "P5E_CPU0_P1_TX_C_DN<7>")
		)
		(pad "CK10" smd circle
			(at -0.797306 -1.431798)
			(size 0.381 0.381)
			(layers "F.Cu" "F.Mask" "F.Paste")
			(net "P5E_CPU0_P1_TX_BUF_DN<7>")
		)
		(pad "CK29" smd circle
			(at -0.797306 2.032254)
			(size 0.381 0.381)
			(layers "F.Cu" "F.Mask" "F.Paste")
			(net "P5E_CPU0_P1_RX_DN<7>")
		)
		(pad "CL1" smd oval
			(at -0.94996 -3.938524)
			(size 0.254 0.3302)
			(layers "F.Cu" "F.Mask" "F.Paste")
			(net "P5E_CPU0_P1_RX_BUF_DP<7>")
		)
		(pad "CL35" smd oval
			(at -0.94996 3.940048)
			(size 0.254 0.3302)
			(layers "F.Cu" "F.Mask" "F.Paste")
			(net "P5E_CPU0_P1_TX_C_DP<7>")
		)
		(pad "CM4" smd circle
			(at -1.197356 -2.817368)
			(size 0.381 0.381)
			(layers "F.Cu" "F.Mask" "F.Paste")
			(net "GND")
		)
		(pad "CM13" smd circle
			(at -1.197356 -0.79629)
			(size 0.3048 0.3048)
			(layers "F.Cu" "F.Mask" "F.Paste")
			(net "GND")
		)
		(pad "CM17" smd circle
			(at -1.197356 -0.296164)
			(size 0.3048 0.3048)
			(layers "F.Cu" "F.Mask" "F.Paste")
			(net "P1V8_CPU0_RT1_1A")
		)
		(pad "CM20" smd circle
			(at -1.197356 0.203708)
			(size 0.3048 0.3048)
			(layers "F.Cu" "F.Mask" "F.Paste")
			(net "P1V8_CPU0_RT1_1A")
		)
		(pad "CM22" smd circle
			(at -1.197356 0.703834)
			(size 0.3048 0.3048)
			(layers "F.Cu" "F.Mask" "F.Paste")
			(net "GND")
		)
		(pad "CM32" smd circle
			(at -1.197356 2.724912)
			(size 0.381 0.381)
			(layers "F.Cu" "F.Mask" "F.Paste")
			(net "GND")
		)
		(pad "CN2" smd circle
			(at -1.249934 -3.41884)
			(size 0.3048 0.3048)
			(layers "F.Cu" "F.Mask" "F.Paste")
			(net "GND")
		)
		(pad "CN34" smd circle
			(at -1.249934 3.420364)
			(size 0.3048 0.3048)
			(layers "F.Cu" "F.Mask" "F.Paste")
			(net "GND")
		)
		(pad "CP1" smd oval
			(at -1.549908 -3.938524)
			(size 0.254 0.3302)
			(layers "F.Cu" "F.Mask" "F.Paste")
			(net "GND")
		)
		(pad "CP35" smd oval
			(at -1.549908 3.940048)
			(size 0.254 0.3302)
			(layers "F.Cu" "F.Mask" "F.Paste")
			(net "GND")
		)
		(pad "CR7" smd circle
			(at -1.597406 -2.12471)
			(size 0.381 0.381)
			(layers "F.Cu" "F.Mask" "F.Paste")
			(net "P5E_CPU0_P1_TX_BUF_DP<6>")
		)
		(pad "CR26" smd circle
			(at -1.597406 1.339342)
			(size 0.381 0.381)
			(layers "F.Cu" "F.Mask" "F.Paste")
			(net "P5E_CPU0_P1_RX_DP<6>")
		)
		(pad "CT2" smd circle
			(at -1.849882 -3.41884)
			(size 0.3048 0.3048)
			(layers "F.Cu" "F.Mask" "F.Paste")
			(net "P5E_CPU0_P1_RX_BUF_DN<6>")
		)
		(pad "CT34" smd circle
			(at -1.849882 3.420364)
			(size 0.3048 0.3048)
			(layers "F.Cu" "F.Mask" "F.Paste")
			(net "P5E_CPU0_P1_TX_C_DN<6>")
		)
		(pad "CU10" smd circle
			(at -1.997456 -1.431798)
			(size 0.381 0.381)
			(layers "F.Cu" "F.Mask" "F.Paste")
			(net "P5E_CPU0_P1_TX_BUF_DN<6>")
		)
		(pad "CU29" smd circle
			(at -1.997456 2.032254)
			(size 0.381 0.381)
			(layers "F.Cu" "F.Mask" "F.Paste")
			(net "P5E_CPU0_P1_RX_DN<6>")
		)
		(pad "CV1" smd oval
			(at -2.15011 -3.938524)
			(size 0.254 0.3302)
			(layers "F.Cu" "F.Mask" "F.Paste")
			(net "P5E_CPU0_P1_RX_BUF_DP<6>")
		)
		(pad "CV35" smd oval
			(at -2.15011 3.940048)
			(size 0.254 0.3302)
			(layers "F.Cu" "F.Mask" "F.Paste")
			(net "P5E_CPU0_P1_TX_C_DP<6>")
		)
		(pad "CW4" smd circle
			(at -2.397506 -2.817368)
			(size 0.381 0.381)
			(layers "F.Cu" "F.Mask" "F.Paste")
			(net "GND")
		)
		(pad "CW13" smd circle
			(at -2.397506 -0.79629)
			(size 0.3048 0.3048)
			(layers "F.Cu" "F.Mask" "F.Paste")
			(net "GND")
		)
		(pad "CW17" smd circle
			(at -2.397506 -0.296164)
			(size 0.3048 0.3048)
			(layers "F.Cu" "F.Mask" "F.Paste")
			(net "P0V9_CPU0_RT_2D")
		)
		(pad "CW20" smd circle
			(at -2.397506 0.203708)
			(size 0.3048 0.3048)
			(layers "F.Cu" "F.Mask" "F.Paste")
			(net "P0V9_CPU0_RT_2D")
		)
		(pad "CW22" smd circle
			(at -2.397506 0.703834)
			(size 0.3048 0.3048)
			(layers "F.Cu" "F.Mask" "F.Paste")
			(net "GND")
		)
		(pad "CW32" smd circle
			(at -2.397506 2.724912)
			(size 0.381 0.381)
			(layers "F.Cu" "F.Mask" "F.Paste")
			(net "GND")
		)
		(pad "CY2" smd circle
			(at -2.450084 -3.41884)
			(size 0.3048 0.3048)
			(layers "F.Cu" "F.Mask" "F.Paste")
			(net "GND")
		)
		(pad "CY34" smd circle
			(at -2.450084 3.420364)
			(size 0.3048 0.3048)
			(layers "F.Cu" "F.Mask" "F.Paste")
			(net "GND")
		)
		(pad "D1" smd oval
			(at 10.450068 -3.938524)
			(size 0.254 0.3302)
			(layers "F.Cu" "F.Mask" "F.Paste")
			(net "NCF_CPU0_P1_GND")
		)
		(pad "D35" smd oval
			(at 10.450068 3.940048)
			(size 0.254 0.3302)
			(layers "F.Cu" "F.Mask" "F.Paste")
			(net "NCF_CPU0_P1_GND")
		)
		(pad "DA1" smd oval
			(at -2.750058 -3.938524)
			(size 0.254 0.3302)
			(layers "F.Cu" "F.Mask" "F.Paste")
			(net "GND")
		)
		(pad "DA35" smd oval
			(at -2.750058 3.940048)
			(size 0.254 0.3302)
			(layers "F.Cu" "F.Mask" "F.Paste")
			(net "GND")
		)
		(pad "DB7" smd circle
			(at -2.797302 -2.12471)
			(size 0.381 0.381)
			(layers "F.Cu" "F.Mask" "F.Paste")
			(net "P5E_CPU0_P1_TX_BUF_DP<5>")
		)
		(pad "DB26" smd circle
			(at -2.797302 1.339342)
			(size 0.381 0.381)
			(layers "F.Cu" "F.Mask" "F.Paste")
			(net "P5E_CPU0_P1_RX_DP<5>")
		)
		(pad "DC2" smd circle
			(at -3.050032 -3.41884)
			(size 0.3048 0.3048)
			(layers "F.Cu" "F.Mask" "F.Paste")
			(net "P5E_CPU0_P1_RX_BUF_DN<5>")
		)
		(pad "DC34" smd circle
			(at -3.050032 3.420364)
			(size 0.3048 0.3048)
			(layers "F.Cu" "F.Mask" "F.Paste")
			(net "P5E_CPU0_P1_TX_C_DN<5>")
		)
		(pad "DD10" smd circle
			(at -3.197352 -1.431798)
			(size 0.381 0.381)
			(layers "F.Cu" "F.Mask" "F.Paste")
			(net "P5E_CPU0_P1_TX_BUF_DN<5>")
		)
		(pad "DD29" smd circle
			(at -3.197352 2.032254)
			(size 0.381 0.381)
			(layers "F.Cu" "F.Mask" "F.Paste")
			(net "P5E_CPU0_P1_RX_DN<5>")
		)
		(pad "DE1" smd oval
			(at -3.350006 -3.938524)
			(size 0.254 0.3302)
			(layers "F.Cu" "F.Mask" "F.Paste")
			(net "P5E_CPU0_P1_RX_BUF_DP<5>")
		)
		(pad "DE35" smd oval
			(at -3.350006 3.940048)
			(size 0.254 0.3302)
			(layers "F.Cu" "F.Mask" "F.Paste")
			(net "P5E_CPU0_P1_TX_C_DP<5>")
		)
		(pad "DF4" smd circle
			(at -3.597402 -2.817368)
			(size 0.381 0.381)
			(layers "F.Cu" "F.Mask" "F.Paste")
			(net "GND")
		)
		(pad "DF13" smd circle
			(at -3.597402 -0.79629)
			(size 0.3048 0.3048)
			(layers "F.Cu" "F.Mask" "F.Paste")
			(net "GND")
		)
		(pad "DF17" smd circle
			(at -3.597402 -0.296164)
			(size 0.3048 0.3048)
			(layers "F.Cu" "F.Mask" "F.Paste")
			(net "P0V9_CPU0_RT1_2A_2D")
		)
		(pad "DF20" smd circle
			(at -3.597402 0.203708)
			(size 0.3048 0.3048)
			(layers "F.Cu" "F.Mask" "F.Paste")
			(net "P0V9_CPU0_RT1_2A_2D")
		)
		(pad "DF22" smd circle
			(at -3.597402 0.703834)
			(size 0.3048 0.3048)
			(layers "F.Cu" "F.Mask" "F.Paste")
			(net "GND")
		)
		(pad "DF32" smd circle
			(at -3.597402 2.724912)
			(size 0.381 0.381)
			(layers "F.Cu" "F.Mask" "F.Paste")
			(net "GND")
		)
		(pad "DG2" smd circle
			(at -3.64998 -3.41884)
			(size 0.3048 0.3048)
			(layers "F.Cu" "F.Mask" "F.Paste")
			(net "GND")
		)
		(pad "DG34" smd circle
			(at -3.64998 3.420364)
			(size 0.3048 0.3048)
			(layers "F.Cu" "F.Mask" "F.Paste")
			(net "GND")
		)
		(pad "DH1" smd oval
			(at -3.949954 -3.938524)
			(size 0.254 0.3302)
			(layers "F.Cu" "F.Mask" "F.Paste")
			(net "GND")
		)
		(pad "DH35" smd oval
			(at -3.949954 3.940048)
			(size 0.254 0.3302)
			(layers "F.Cu" "F.Mask" "F.Paste")
			(net "GND")
		)
		(pad "DJ7" smd circle
			(at -3.997452 -2.12471)
			(size 0.381 0.381)
			(layers "F.Cu" "F.Mask" "F.Paste")
			(net "P5E_CPU0_P1_TX_BUF_DP<4>")
		)
		(pad "DJ26" smd circle
			(at -3.997452 1.339342)
			(size 0.381 0.381)
			(layers "F.Cu" "F.Mask" "F.Paste")
			(net "P5E_CPU0_P1_RX_DP<4>")
		)
		(pad "DK2" smd circle
			(at -4.249928 -3.41884)
			(size 0.3048 0.3048)
			(layers "F.Cu" "F.Mask" "F.Paste")
			(net "P5E_CPU0_P1_RX_BUF_DN<4>")
		)
		(pad "DK34" smd circle
			(at -4.249928 3.420364)
			(size 0.3048 0.3048)
			(layers "F.Cu" "F.Mask" "F.Paste")
			(net "P5E_CPU0_P1_TX_C_DN<4>")
		)
		(pad "DL10" smd circle
			(at -4.397502 -1.431798)
			(size 0.381 0.381)
			(layers "F.Cu" "F.Mask" "F.Paste")
			(net "P5E_CPU0_P1_TX_BUF_DN<4>")
		)
		(pad "DL29" smd circle
			(at -4.397502 2.032254)
			(size 0.381 0.381)
			(layers "F.Cu" "F.Mask" "F.Paste")
			(net "P5E_CPU0_P1_RX_DN<4>")
		)
		(pad "DM1" smd oval
			(at -4.549902 -3.938524)
			(size 0.254 0.3302)
			(layers "F.Cu" "F.Mask" "F.Paste")
			(net "P5E_CPU0_P1_RX_BUF_DP<4>")
		)
		(pad "DM35" smd oval
			(at -4.549902 3.940048)
			(size 0.254 0.3302)
			(layers "F.Cu" "F.Mask" "F.Paste")
			(net "P5E_CPU0_P1_TX_C_DP<4>")
		)
		(pad "DN4" smd circle
			(at -4.797298 -2.817368)
			(size 0.381 0.381)
			(layers "F.Cu" "F.Mask" "F.Paste")
			(net "GND")
		)
		(pad "DN13" smd circle
			(at -4.797298 -0.79629)
			(size 0.3048 0.3048)
			(layers "F.Cu" "F.Mask" "F.Paste")
			(net "GND")
		)
		(pad "DN17" smd circle
			(at -4.797298 -0.296164)
			(size 0.3048 0.3048)
			(layers "F.Cu" "F.Mask" "F.Paste")
			(net "P0V9_CPU0_RT1_2A")
		)
		(pad "DN20" smd circle
			(at -4.797298 0.203708)
			(size 0.3048 0.3048)
			(layers "F.Cu" "F.Mask" "F.Paste")
			(net "P0V9_CPU0_RT1_2A")
		)
		(pad "DN22" smd circle
			(at -4.797298 0.703834)
			(size 0.3048 0.3048)
			(layers "F.Cu" "F.Mask" "F.Paste")
			(net "GND")
		)
		(pad "DN32" smd circle
			(at -4.797298 2.724912)
			(size 0.381 0.381)
			(layers "F.Cu" "F.Mask" "F.Paste")
			(net "GND")
		)
		(pad "DP2" smd circle
			(at -4.849876 -3.41884)
			(size 0.3048 0.3048)
			(layers "F.Cu" "F.Mask" "F.Paste")
			(net "GND")
		)
		(pad "DP34" smd circle
			(at -4.849876 3.420364)
			(size 0.3048 0.3048)
			(layers "F.Cu" "F.Mask" "F.Paste")
			(net "GND")
		)
		(pad "DR1" smd oval
			(at -5.150104 -3.938524)
			(size 0.254 0.3302)
			(layers "F.Cu" "F.Mask" "F.Paste")
			(net "GND")
		)
		(pad "DR35" smd oval
			(at -5.150104 3.940048)
			(size 0.254 0.3302)
			(layers "F.Cu" "F.Mask" "F.Paste")
			(net "GND")
		)
		(pad "DT7" smd circle
			(at -5.197348 -2.12471)
			(size 0.381 0.381)
			(layers "F.Cu" "F.Mask" "F.Paste")
			(net "P5E_CPU0_P1_TX_BUF_DP<3>")
		)
		(pad "DT26" smd circle
			(at -5.197348 1.339342)
			(size 0.381 0.381)
			(layers "F.Cu" "F.Mask" "F.Paste")
			(net "P5E_CPU0_P1_RX_DP<3>")
		)
		(pad "DU2" smd circle
			(at -5.450078 -3.41884)
			(size 0.3048 0.3048)
			(layers "F.Cu" "F.Mask" "F.Paste")
			(net "P5E_CPU0_P1_RX_BUF_DN<3>")
		)
		(pad "DU34" smd circle
			(at -5.450078 3.420364)
			(size 0.3048 0.3048)
			(layers "F.Cu" "F.Mask" "F.Paste")
			(net "P5E_CPU0_P1_TX_C_DN<3>")
		)
		(pad "DV10" smd circle
			(at -5.597398 -1.431798)
			(size 0.381 0.381)
			(layers "F.Cu" "F.Mask" "F.Paste")
			(net "P5E_CPU0_P1_TX_BUF_DN<3>")
		)
		(pad "DV29" smd circle
			(at -5.597398 2.032254)
			(size 0.381 0.381)
			(layers "F.Cu" "F.Mask" "F.Paste")
			(net "P5E_CPU0_P1_RX_DN<3>")
		)
		(pad "DW1" smd oval
			(at -5.750052 -3.938524)
			(size 0.254 0.3302)
			(layers "F.Cu" "F.Mask" "F.Paste")
			(net "P5E_CPU0_P1_RX_BUF_DP<3>")
		)
		(pad "DW35" smd oval
			(at -5.750052 3.940048)
			(size 0.254 0.3302)
			(layers "F.Cu" "F.Mask" "F.Paste")
			(net "P5E_CPU0_P1_TX_C_DP<3>")
		)
		(pad "DY4" smd circle
			(at -5.997448 -2.817368)
			(size 0.381 0.381)
			(layers "F.Cu" "F.Mask" "F.Paste")
			(net "GND")
		)
		(pad "DY13" smd circle
			(at -5.997448 -0.79629)
			(size 0.3048 0.3048)
			(layers "F.Cu" "F.Mask" "F.Paste")
			(net "GND")
		)
		(pad "DY17" smd circle
			(at -5.997448 -0.296164)
			(size 0.3048 0.3048)
			(layers "F.Cu" "F.Mask" "F.Paste")
			(net "P0V9_CPU0_RT1_2A")
		)
		(pad "DY20" smd circle
			(at -5.997448 0.203708)
			(size 0.3048 0.3048)
			(layers "F.Cu" "F.Mask" "F.Paste")
			(net "P0V9_CPU0_RT1_2A")
		)
		(pad "DY22" smd circle
			(at -5.997448 0.703834)
			(size 0.3048 0.3048)
			(layers "F.Cu" "F.Mask" "F.Paste")
			(net "GND")
		)
	)
)
